# S9S_MB_2U (Grand Teton) — schematic netlist excerpt (pin names and nets, part order shuffled) for the footprints in the layout excerpt that follows; sources: Cadence DE-HDL packaged netlist, KiCad conversion of 03242023_DA0F0TMBIJ0_F0T_Motherboard_J_brd_V01_OCP.brd

R1254  Q_RES  10K 1% CHIP  pkg 0402LF  page 204 : A = PGPPA_AUX ; B = IRQ_LPC_SERIRQ_ESPI_CS1_N

X16  TP_TDR_4P_FTS  TP_TDR_4P_DIP EMPTY  pkg TH  page 309
  S1  = TDR_DIFF_100_IN3_DP
  P1  = T1_GND
  P2  = T1_GND
  S2  = TDR_DIFF_100_IN3_DN

(kicad_pcb
	(version 20260206)
	(generator "pcbnew")
	(generator_version "10.0")
	(general
		(thickness 1.6)
		(legacy_teardrops no)
	)
	(paper "A4")
	(title_block
		(title "03242023_DA0F0TMBIJ0_F0T_Motherboard_J_brd_V01_OCP.brd")
		(comment 1 "Grand Teton / footprints 1498-1499 of 6105")
	)
	(layers
		(0 "F.Cu" signal "TOP")
		(4 "In1.Cu" signal "GND")
		(6 "In2.Cu" signal "IN1")
		(8 "In3.Cu" signal "GND1")
		(10 "In4.Cu" signal "IN2")
		(12 "In5.Cu" signal "GND2")
		(14 "In6.Cu" signal "IN3")
		(16 "In7.Cu" signal "GND3")
		(18 "In8.Cu" signal "VCC")
		(20 "In9.Cu" signal "VCC1")
		(22 "In10.Cu" signal "GND4")
		(24 "In11.Cu" signal "IN4")
		(26 "In12.Cu" signal "GND5")
		(28 "In13.Cu" signal "IN5")
		(30 "In14.Cu" signal "GND6")
		(32 "In15.Cu" signal "IN6")
		(34 "In16.Cu" signal "GND7")
		(2 "B.Cu" signal "BOTTOM")
		(9 "F.Adhes" user "F.Adhesive")
		(11 "B.Adhes" user "B.Adhesive")
		(13 "F.Paste" user "Package Geometry/Pastemask Top")
		(15 "B.Paste" user "Package Geometry/Pastemask Bottom")
		(5 "F.SilkS" user "Ref Des/Silkscreen Top")
		(7 "B.SilkS" user "Ref Des/Silkscreen Bottom")
		(1 "F.Mask" user "Board Geometry/Soldermask Top")
		(3 "B.Mask" user "Board Geometry/Soldermask Bottom")
		(17 "Dwgs.User" user "User.Drawings")
		(19 "Cmts.User" user "User.Comments")
		(21 "Eco1.User" user "User.Eco1")
		(23 "Eco2.User" user "User.Eco2")
		(25 "Edge.Cuts" user "Board Geometry/Outline")
		(27 "Margin" user)
		(31 "F.CrtYd" user "Package Geometry/Place Bound Top")
		(29 "B.CrtYd" user "Package Geometry/Place Bound Bottom")
		(35 "F.Fab" user "Ref Des/Assembly Top")
		(33 "B.Fab" user "Ref Des/Assembly Bottom")
	)
	(footprint ""
		(layer "F.Cu")
		(at 331.029056 -19.37766 90)
		(property "Reference" "R1254"
			(at 0 0 90)
			(layer "F.SilkS")
			(hide yes)
			(effects
				(font
					(size 1.27 1.27)
				)
			)
		)
		(property "Value" ""
			(at 0 0 90)
			(layer "F.Fab")
			(effects
				(font
					(size 1.27 1.27)
				)
			)
		)
		(duplicate_pad_numbers_are_jumpers no)
		(fp_line
			(start 0.7874 -0.4064)
			(end 0.7874 0.4064)
			(stroke
				(width 0.1524)
				(type default)
			)
			(layer "F.SilkS")
		)
		(fp_line
			(start -0.7874 -0.4064)
			(end 0.7874 -0.4064)
			(stroke
				(width 0.1524)
				(type default)
			)
			(layer "F.SilkS")
		)
		(fp_line
			(start 0.7874 0.4064)
			(end -0.7874 0.4064)
			(stroke
				(width 0.1524)
				(type default)
			)
			(layer "F.SilkS")
		)
		(fp_line
			(start -0.7874 0.4064)
			(end -0.7874 -0.4064)
			(stroke
				(width 0.1524)
				(type default)
			)
			(layer "F.SilkS")
		)
		(fp_line
			(start -0.12065 -0.305054)
			(end -0.12065 -0.2794)
			(stroke
				(width 0.1)
				(type default)
			)
			(layer "F.Fab")
		)
		(fp_line
			(start -0.67945 -0.305054)
			(end -0.12065 -0.305054)
			(stroke
				(width 0.1)
				(type default)
			)
			(layer "F.Fab")
		)
		(fp_line
			(start 0.67945 -0.3048)
			(end 0.67945 0.3048)
			(stroke
				(width 0.1)
				(type default)
			)
			(layer "F.Fab")
		)
		(fp_line
			(start 0.12065 -0.3048)
			(end 0.67945 -0.3048)
			(stroke
				(width 0.1)
				(type default)
			)
			(layer "F.Fab")
		)
		(fp_line
			(start 0.12065 -0.2794)
			(end 0.12065 -0.3048)
			(stroke
				(width 0.1)
				(type default)
			)
			(layer "F.Fab")
		)
		(fp_line
			(start -0.12065 -0.2794)
			(end 0.12065 -0.2794)
			(stroke
				(width 0.1)
				(type default)
			)
			(layer "F.Fab")
		)
		(fp_line
			(start 0.120396 0.2794)
			(end -0.12065 0.2794)
			(stroke
				(width 0.1)
				(type default)
			)
			(layer "F.Fab")
		)
		(fp_line
			(start -0.12065 0.2794)
			(end -0.12065 0.3048)
			(stroke
				(width 0.1)
				(type default)
			)
			(layer "F.Fab")
		)
		(fp_line
			(start 0.67945 0.3048)
			(end 0.120396 0.3048)
			(stroke
				(width 0.1)
				(type default)
			)
			(layer "F.Fab")
		)
		(fp_line
			(start 0.120396 0.3048)
			(end 0.120396 0.2794)
			(stroke
				(width 0.1)
				(type default)
			)
			(layer "F.Fab")
		)
		(fp_line
			(start -0.12065 0.3048)
			(end -0.67945 0.3048)
			(stroke
				(width 0.1)
				(type default)
			)
			(layer "F.Fab")
		)
		(fp_line
			(start -0.67945 0.3048)
			(end -0.67945 -0.305054)
			(stroke
				(width 0.1)
				(type default)
			)
			(layer "F.Fab")
		)
		(pad "1" smd circle
			(at -0.40005 0 90)
			(size 0 0)
			(layers "F.Cu" "F.Mask" "F.Paste")
			(net "PGPPA_AUX")
		)
		(pad "2" smd circle
			(at 0.40005 0 90)
			(size 0 0)
			(layers "F.Cu" "F.Mask" "F.Paste")
			(net "IRQ_LPC_SERIRQ_ESPI_CS1_N")
		)
	)
	(footprint ""
		(layer "F.Cu")
		(at 490.57433 2.370328 -90)
		(property "Reference" "X16"
			(at -1.342644 2.821178 90)
			(unlocked yes)
			(layer "F.SilkS")
			(effects
				(font
					(size 0.7874 0.5842)
					(thickness 0.1524)
				)
				(justify left)
			)
		)
		(property "Value" ""
			(at 0 0 270)
			(layer "F.Fab")
			(effects
				(font
					(size 1.27 1.27)
				)
			)
		)
		(property "Device Type" "TP_TDR_4P_FTS_TH-TP_TDR_4P_DIPA"
			(at 1.30175 1.27 0)
			(unlocked yes)
			(layer "F.Fab")
			(hide yes)
			(effects
				(font
					(size 0.635 0.4064)
					(thickness 0.1524)
				)
			)
		)
		(property "User Part Number" "N_A"
			(at 1.30175 1.27 0)
			(unlocked yes)
			(layer "Cmts.User")
			(hide yes)
			(effects
				(font
					(size 0.635 0.4064)
					(thickness 0.1524)
				)
			)
		)
		(duplicate_pad_numbers_are_jumpers no)
		(fp_line
			(start 0 3.81)
			(end 2.54 3.81)
			(stroke
				(width 0.1524)
				(type default)
			)
			(layer "F.SilkS")
		)
		(fp_line
			(start 2.54 3.81)
			(end 2.54 3.6703)
			(stroke
				(width 0.1524)
				(type default)
			)
			(layer "F.SilkS")
		)
		(fp_line
			(start 0 3.175)
			(end 0 3.81)
			(stroke
				(width 0.1524)
				(type default)
			)
			(layer "F.SilkS")
		)
		(fp_line
			(start 2.54 1.4097)
			(end 2.54 1.1303)
			(stroke
				(width 0.1524)
				(type default)
			)
			(layer "F.SilkS")
		)
		(fp_line
			(start 0 0.635)
			(end 0 1.905)
			(stroke
				(width 0.1524)
				(type default)
			)
			(layer "F.SilkS")
		)
		(fp_line
			(start 2.54 -1.1303)
			(end 2.54 -1.27)
			(stroke
				(width 0.1524)
				(type default)
			)
			(layer "F.SilkS")
		)
		(fp_line
			(start 0 -1.27)
			(end 0 -0.635)
			(stroke
				(width 0.1524)
				(type default)
			)
			(layer "F.SilkS")
		)
		(fp_line
			(start 2.54 -1.27)
			(end 0 -1.27)
			(stroke
				(width 0.1524)
				(type default)
			)
			(layer "F.SilkS")
		)
		(fp_poly
			(pts
				(xy -1.247648 0.03175) (xy -2.771648 0.79375) (xy -2.771648 -0.73025)
			)
			(stroke
				(width 0)
				(type default)
			)
			(fill yes)
			(layer "F.SilkS")
		)
		(fp_line
			(start 0 3.81)
			(end 2.54 3.81)
			(stroke
				(width 0.1)
				(type default)
			)
			(layer "F.Fab")
		)
		(fp_line
			(start 2.54 3.81)
			(end 2.54 -1.27)
			(stroke
				(width 0.1)
				(type default)
			)
			(layer "F.Fab")
		)
		(fp_line
			(start 0 -1.27)
			(end 0 3.81)
			(stroke
				(width 0.1)
				(type default)
			)
			(layer "F.Fab")
		)
		(fp_line
			(start 2.54 -1.27)
			(end 0 -1.27)
			(stroke
				(width 0.1)
				(type default)
			)
			(layer "F.Fab")
		)
		(fp_poly
			(pts
				(xy -0.761746 0) (xy -2.285746 -0.762) (xy -2.285746 0.762)
			)
			(stroke
				(width 0)
				(type default)
			)
			(fill yes)
			(layer "F.Fab")
		)
		(pad "1" thru_hole circle
			(at 0 0 270)
			(size 1.0033 1.0033)
			(drill 0.249936)
			(layers "*.Cu" "*.Mask")
			(remove_unused_layers no)
			(net "TDR_DIFF_100_IN3_DP")
			(clearance 0.10795)
			(thermal_gap 0.10795)
			(padstack
				(mode front_inner_back)
				(layer "Inner"
					(shape circle)
					(size 0.8001 0.8001)
					(clearance 0.1524)
				)
				(layer "B.Cu"
					(shape circle)
					(size 1.0033 1.0033)
					(clearance 0.10795)
				)
			)
		)
		(pad "2" thru_hole circle
			(at 2.54 0 270)
			(size 1.9939 1.9939)
			(drill 0.249936)
			(layers "*.Cu" "*.Mask")
			(remove_unused_layers no)
			(net "T1_GND")
			(clearance 0.10795)
			(thermal_gap 0.10795)
			(padstack
				(mode front_inner_back)
				(layer "Inner"
					(shape circle)
					(size 0.8001 0.8001)
					(clearance 0.1524)
				)
				(layer "B.Cu"
					(shape circle)
					(size 1.9939 1.9939)
					(clearance 0.10795)
				)
			)
		)
		(pad "3" thru_hole circle
			(at 2.54 2.54 270)
			(size 1.9939 1.9939)
			(drill 0.249936)
			(layers "*.Cu" "*.Mask")
			(remove_unused_layers no)
			(net "T1_GND")
			(clearance 0.10795)
			(thermal_gap 0.10795)
			(padstack
				(mode front_inner_back)
				(layer "Inner"
					(shape circle)
					(size 0.8001 0.8001)
					(clearance 0.1524)
				)
				(layer "B.Cu"
					(shape circle)
					(size 1.9939 1.9939)
					(clearance 0.10795)
				)
			)
		)
		(pad "4" thru_hole circle
			(at 0 2.54 270)
			(size 1.0033 1.0033)
			(drill 0.249936)
			(layers "*.Cu" "*.Mask")
			(remove_unused_layers no)
			(net "TDR_DIFF_100_IN3_DN")
			(clearance 0.10795)
			(thermal_gap 0.10795)
			(padstack
				(mode front_inner_back)
				(layer "Inner"
					(shape circle)
					(size 0.8001 0.8001)
					(clearance 0.1524)
				)
				(layer "B.Cu"
					(shape circle)
					(size 1.0033 1.0033)
					(clearance 0.10795)
				)
			)
		)
	)
)
